(kicad_pcb
	(version 20260206)
	(generator "pcbnew")
	(generator_version "10.0")
	(general
		(thickness 1.6)
		(legacy_teardrops no)
	)
	(paper "A4")
	(title_block
		(title "04192023_DAF0TMB3IC0_F0TG_MB_C_brd_V02_OCP.brd")
		(comment 1 "Grand Teton / footprints 7832-7838 of 8354")
	)
	(layers
		(0 "F.Cu" signal "TOP")
		(4 "In1.Cu" signal "GND")
		(6 "In2.Cu" signal "IN1")
		(8 "In3.Cu" signal "GND1")
		(10 "In4.Cu" signal "IN2")
		(12 "In5.Cu" signal "GND2")
		(14 "In6.Cu" signal "IN3")
		(16 "In7.Cu" signal "GND3")
		(18 "In8.Cu" signal "VCC")
		(20 "In9.Cu" signal "VCC1")
		(22 "In10.Cu" signal "GND4")
		(24 "In11.Cu" signal "IN4")
		(26 "In12.Cu" signal "GND5")
		(28 "In13.Cu" signal "IN5")
		(30 "In14.Cu" signal "GND6")
		(32 "In15.Cu" signal "IN6")
		(34 "In16.Cu" signal "GND7")
		(2 "B.Cu" signal "BOTTOM")
		(9 "F.Adhes" user "F.Adhesive")
		(11 "B.Adhes" user "B.Adhesive")
		(13 "F.Paste" user "Package Geometry/Pastemask Top")
		(15 "B.Paste" user "Package Geometry/Pastemask Bottom")
		(5 "F.SilkS" user "Ref Des/Silkscreen Top")
		(7 "B.SilkS" user "Ref Des/Silkscreen Bottom")
		(1 "F.Mask" user "Board Geometry/Soldermask Top")
		(3 "B.Mask" user "Board Geometry/Soldermask Bottom")
		(17 "Dwgs.User" user "User.Drawings")
		(19 "Cmts.User" user "User.Comments")
		(21 "Eco1.User" user "User.Eco1")
		(23 "Eco2.User" user "User.Eco2")
		(25 "Edge.Cuts" user "Board Geometry/Outline")
		(27 "Margin" user)
		(31 "F.CrtYd" user "Package Geometry/Place Bound Top")
		(29 "B.CrtYd" user "Package Geometry/Place Bound Bottom")
		(35 "F.Fab" user "Ref Des/Assembly Top")
		(33 "B.Fab" user "Ref Des/Assembly Bottom")
	)
	(footprint ""
		(layer "B.Cu")
		(at 180.271674 -194.885564 180)
		(property "Reference" "R775"
			(at 0 0 0)
			(layer "B.SilkS")
			(hide yes)
			(effects
				(font
					(size 1.27 1.27)
				)
				(justify mirror)
			)
		)
		(property "Value" ""
			(at 0 0 0)
			(layer "B.Fab")
			(effects
				(font
					(size 1.27 1.27)
				)
				(justify mirror)
			)
		)
		(duplicate_pad_numbers_are_jumpers no)
		(fp_line
			(start 0.7874 0.4064)
			(end 0.7874 -0.4064)
			(stroke
				(width 0.1524)
				(type default)
			)
			(layer "B.SilkS")
		)
		(fp_line
			(start 0.7874 -0.4064)
			(end -0.7874 -0.4064)
			(stroke
				(width 0.1524)
				(type default)
			)
			(layer "B.SilkS")
		)
		(fp_line
			(start -0.7874 0.4064)
			(end 0.7874 0.4064)
			(stroke
				(width 0.1524)
				(type default)
			)
			(layer "B.SilkS")
		)
		(fp_line
			(start -0.7874 -0.4064)
			(end -0.7874 0.4064)
			(stroke
				(width 0.1524)
				(type default)
			)
			(layer "B.SilkS")
		)
		(fp_line
			(start 0.67945 0.3048)
			(end 0.67945 -0.305054)
			(stroke
				(width 0.1)
				(type default)
			)
			(layer "B.Fab")
		)
		(fp_line
			(start 0.67945 -0.305054)
			(end 0.12065 -0.305054)
			(stroke
				(width 0.1)
				(type default)
			)
			(layer "B.Fab")
		)
		(fp_line
			(start 0.12065 0.3048)
			(end 0.67945 0.3048)
			(stroke
				(width 0.1)
				(type default)
			)
			(layer "B.Fab")
		)
		(fp_line
			(start 0.12065 0.2794)
			(end 0.12065 0.3048)
			(stroke
				(width 0.1)
				(type default)
			)
			(layer "B.Fab")
		)
		(fp_line
			(start 0.12065 -0.2794)
			(end -0.12065 -0.2794)
			(stroke
				(width 0.1)
				(type default)
			)
			(layer "B.Fab")
		)
		(fp_line
			(start 0.12065 -0.305054)
			(end 0.12065 -0.2794)
			(stroke
				(width 0.1)
				(type default)
			)
			(layer "B.Fab")
		)
		(fp_line
			(start -0.120396 0.3048)
			(end -0.120396 0.2794)
			(stroke
				(width 0.1)
				(type default)
			)
			(layer "B.Fab")
		)
		(fp_line
			(start -0.120396 0.2794)
			(end 0.12065 0.2794)
			(stroke
				(width 0.1)
				(type default)
			)
			(layer "B.Fab")
		)
		(fp_line
			(start -0.12065 -0.2794)
			(end -0.12065 -0.3048)
			(stroke
				(width 0.1)
				(type default)
			)
			(layer "B.Fab")
		)
		(fp_line
			(start -0.12065 -0.3048)
			(end -0.67945 -0.3048)
			(stroke
				(width 0.1)
				(type default)
			)
			(layer "B.Fab")
		)
		(fp_line
			(start -0.67945 0.3048)
			(end -0.120396 0.3048)
			(stroke
				(width 0.1)
				(type default)
			)
			(layer "B.Fab")
		)
		(fp_line
			(start -0.67945 -0.3048)
			(end -0.67945 0.3048)
			(stroke
				(width 0.1)
				(type default)
			)
			(layer "B.Fab")
		)
		(pad "1" smd circle
			(at 0.40005 0)
			(size 0 0)
			(layers "B.Cu" "B.Mask" "B.Paste")
			(net "PD_CHI_CPU1_DIMM_SAA")
		)
		(pad "2" smd circle
			(at -0.40005 0)
			(size 0 0)
			(layers "B.Cu" "B.Mask" "B.Paste")
			(net "GND")
		)
	)
	(footprint ""
		(layer "B.Cu")
		(at 417.406328 -395.148562 90)
		(property "Reference" "C792"
			(at 0 0 90)
			(layer "B.SilkS")
			(hide yes)
			(effects
				(font
					(size 1.27 1.27)
				)
				(justify mirror)
			)
		)
		(property "Value" ""
			(at 0 0 90)
			(layer "B.Fab")
			(effects
				(font
					(size 1.27 1.27)
				)
				(justify mirror)
			)
		)
		(duplicate_pad_numbers_are_jumpers no)
		(fp_line
			(start 0.299974 -0.150114)
			(end -0.299974 -0.150114)
			(stroke
				(width 0.1)
				(type default)
			)
			(layer "B.Fab")
		)
		(fp_line
			(start -0.299974 -0.150114)
			(end -0.299974 0.150114)
			(stroke
				(width 0.1)
				(type default)
			)
			(layer "B.Fab")
		)
		(fp_line
			(start 0.299974 0.150114)
			(end 0.299974 -0.150114)
			(stroke
				(width 0.1)
				(type default)
			)
			(layer "B.Fab")
		)
		(fp_line
			(start -0.299974 0.150114)
			(end 0.299974 0.150114)
			(stroke
				(width 0.1)
				(type default)
			)
			(layer "B.Fab")
		)
		(pad "1" smd rect
			(at 0.2667 0 270)
			(size 0.3048 0.381)
			(layers "B.Cu" "B.Mask" "B.Paste")
			(net "P0V9_CPU0_RT2_2A")
		)
		(pad "2" smd rect
			(at -0.2667 0 270)
			(size 0.3048 0.381)
			(layers "B.Cu" "B.Mask" "B.Paste")
			(net "GND")
		)
	)
	(footprint ""
		(layer "B.Cu")
		(at 164.403532 -430.59858 -90)
		(property "Reference" "R4123"
			(at 0 0 90)
			(layer "B.SilkS")
			(hide yes)
			(effects
				(font
					(size 1.27 1.27)
				)
				(justify mirror)
			)
		)
		(property "Value" ""
			(at 0 0 90)
			(layer "B.Fab")
			(effects
				(font
					(size 1.27 1.27)
				)
				(justify mirror)
			)
		)
		(duplicate_pad_numbers_are_jumpers no)
		(fp_line
			(start -0.7874 0.4064)
			(end 0.7874 0.4064)
			(stroke
				(width 0.1524)
				(type default)
			)
			(layer "B.SilkS")
		)
		(fp_line
			(start 0.7874 0.4064)
			(end 0.7874 -0.4064)
			(stroke
				(width 0.1524)
				(type default)
			)
			(layer "B.SilkS")
		)
		(fp_line
			(start -0.7874 -0.4064)
			(end -0.7874 0.4064)
			(stroke
				(width 0.1524)
				(type default)
			)
			(layer "B.SilkS")
		)
		(fp_line
			(start 0.7874 -0.4064)
			(end -0.7874 -0.4064)
			(stroke
				(width 0.1524)
				(type default)
			)
			(layer "B.SilkS")
		)
		(fp_line
			(start -0.67945 0.3048)
			(end -0.120396 0.3048)
			(stroke
				(width 0.1)
				(type default)
			)
			(layer "B.Fab")
		)
		(fp_line
			(start -0.120396 0.3048)
			(end -0.120396 0.2794)
			(stroke
				(width 0.1)
				(type default)
			)
			(layer "B.Fab")
		)
		(fp_line
			(start 0.12065 0.3048)
			(end 0.67945 0.3048)
			(stroke
				(width 0.1)
				(type default)
			)
			(layer "B.Fab")
		)
		(fp_line
			(start 0.67945 0.3048)
			(end 0.67945 -0.305054)
			(stroke
				(width 0.1)
				(type default)
			)
			(layer "B.Fab")
		)
		(fp_line
			(start -0.120396 0.2794)
			(end 0.12065 0.2794)
			(stroke
				(width 0.1)
				(type default)
			)
			(layer "B.Fab")
		)
		(fp_line
			(start 0.12065 0.2794)
			(end 0.12065 0.3048)
			(stroke
				(width 0.1)
				(type default)
			)
			(layer "B.Fab")
		)
		(fp_line
			(start -0.12065 -0.2794)
			(end -0.12065 -0.3048)
			(stroke
				(width 0.1)
				(type default)
			)
			(layer "B.Fab")
		)
		(fp_line
			(start 0.12065 -0.2794)
			(end -0.12065 -0.2794)
			(stroke
				(width 0.1)
				(type default)
			)
			(layer "B.Fab")
		)
		(fp_line
			(start -0.67945 -0.3048)
			(end -0.67945 0.3048)
			(stroke
				(width 0.1)
				(type default)
			)
			(layer "B.Fab")
		)
		(fp_line
			(start -0.12065 -0.3048)
			(end -0.67945 -0.3048)
			(stroke
				(width 0.1)
				(type default)
			)
			(layer "B.Fab")
		)
		(fp_line
			(start 0.12065 -0.305054)
			(end 0.12065 -0.2794)
			(stroke
				(width 0.1)
				(type default)
			)
			(layer "B.Fab")
		)
		(fp_line
			(start 0.67945 -0.305054)
			(end 0.12065 -0.305054)
			(stroke
				(width 0.1)
				(type default)
			)
			(layer "B.Fab")
		)
		(pad "1" smd circle
			(at 0.40005 0 90)
			(size 0 0)
			(layers "B.Cu" "B.Mask" "B.Paste")
			(net "P3V3_AUX")
		)
		(pad "2" smd circle
			(at -0.40005 0 90)
			(size 0 0)
			(layers "B.Cu" "B.Mask" "B.Paste")
			(net "GPU_3V3IO_RSVD1_FFU")
		)
	)
	(footprint ""
		(layer "B.Cu")
		(at 410.20619 -395.148562 90)
		(property "Reference" "C778"
			(at 0 0 90)
			(layer "B.SilkS")
			(hide yes)
			(effects
				(font
					(size 1.27 1.27)
				)
				(justify mirror)
			)
		)
		(property "Value" ""
			(at 0 0 90)
			(layer "B.Fab")
			(effects
				(font
					(size 1.27 1.27)
				)
				(justify mirror)
			)
		)
		(duplicate_pad_numbers_are_jumpers no)
		(fp_line
			(start 0.299974 -0.150114)
			(end -0.299974 -0.150114)
			(stroke
				(width 0.1)
				(type default)
			)
			(layer "B.Fab")
		)
		(fp_line
			(start -0.299974 -0.150114)
			(end -0.299974 0.150114)
			(stroke
				(width 0.1)
				(type default)
			)
			(layer "B.Fab")
		)
		(fp_line
			(start 0.299974 0.150114)
			(end 0.299974 -0.150114)
			(stroke
				(width 0.1)
				(type default)
			)
			(layer "B.Fab")
		)
		(fp_line
			(start -0.299974 0.150114)
			(end 0.299974 0.150114)
			(stroke
				(width 0.1)
				(type default)
			)
			(layer "B.Fab")
		)
		(pad "1" smd rect
			(at 0.2667 0 270)
			(size 0.3048 0.381)
			(layers "B.Cu" "B.Mask" "B.Paste")
			(net "P1V8_CPU0_RT2_1A")
		)
		(pad "2" smd rect
			(at -0.2667 0 270)
			(size 0.3048 0.381)
			(layers "B.Cu" "B.Mask" "B.Paste")
			(net "GND")
		)
	)
	(footprint ""
		(layer "B.Cu")
		(at 447.275966 -419.850824 -90)
		(property "Reference" "PR6807"
			(at 0 0 90)
			(layer "B.SilkS")
			(hide yes)
			(effects
				(font
					(size 1.27 1.27)
				)
				(justify mirror)
			)
		)
		(property "Value" ""
			(at 0 0 90)
			(layer "B.Fab")
			(effects
				(font
					(size 1.27 1.27)
				)
				(justify mirror)
			)
		)
		(duplicate_pad_numbers_are_jumpers no)
		(fp_line
			(start -0.7874 0.4064)
			(end 0.7874 0.4064)
			(stroke
				(width 0.1524)
				(type default)
			)
			(layer "B.SilkS")
		)
		(fp_line
			(start 0.7874 0.4064)
			(end 0.7874 -0.4064)
			(stroke
				(width 0.1524)
				(type default)
			)
			(layer "B.SilkS")
		)
		(fp_line
			(start -0.7874 -0.4064)
			(end -0.7874 0.4064)
			(stroke
				(width 0.1524)
				(type default)
			)
			(layer "B.SilkS")
		)
		(fp_line
			(start 0.7874 -0.4064)
			(end -0.7874 -0.4064)
			(stroke
				(width 0.1524)
				(type default)
			)
			(layer "B.SilkS")
		)
		(fp_line
			(start -0.67945 0.3048)
			(end -0.120396 0.3048)
			(stroke
				(width 0.1)
				(type default)
			)
			(layer "B.Fab")
		)
		(fp_line
			(start -0.120396 0.3048)
			(end -0.120396 0.2794)
			(stroke
				(width 0.1)
				(type default)
			)
			(layer "B.Fab")
		)
		(fp_line
			(start 0.12065 0.3048)
			(end 0.67945 0.3048)
			(stroke
				(width 0.1)
				(type default)
			)
			(layer "B.Fab")
		)
		(fp_line
			(start 0.67945 0.3048)
			(end 0.67945 -0.305054)
			(stroke
				(width 0.1)
				(type default)
			)
			(layer "B.Fab")
		)
		(fp_line
			(start -0.120396 0.2794)
			(end 0.12065 0.2794)
			(stroke
				(width 0.1)
				(type default)
			)
			(layer "B.Fab")
		)
		(fp_line
			(start 0.12065 0.2794)
			(end 0.12065 0.3048)
			(stroke
				(width 0.1)
				(type default)
			)
			(layer "B.Fab")
		)
		(fp_line
			(start -0.12065 -0.2794)
			(end -0.12065 -0.3048)
			(stroke
				(width 0.1)
				(type default)
			)
			(layer "B.Fab")
		)
		(fp_line
			(start 0.12065 -0.2794)
			(end -0.12065 -0.2794)
			(stroke
				(width 0.1)
				(type default)
			)
			(layer "B.Fab")
		)
		(fp_line
			(start -0.67945 -0.3048)
			(end -0.67945 0.3048)
			(stroke
				(width 0.1)
				(type default)
			)
			(layer "B.Fab")
		)
		(fp_line
			(start -0.12065 -0.3048)
			(end -0.67945 -0.3048)
			(stroke
				(width 0.1)
				(type default)
			)
			(layer "B.Fab")
		)
		(fp_line
			(start 0.12065 -0.305054)
			(end 0.12065 -0.2794)
			(stroke
				(width 0.1)
				(type default)
			)
			(layer "B.Fab")
		)
		(fp_line
			(start 0.67945 -0.305054)
			(end 0.12065 -0.305054)
			(stroke
				(width 0.1)
				(type default)
			)
			(layer "B.Fab")
		)
		(pad "1" smd circle
			(at 0.40005 0 90)
			(size 0 0)
			(layers "B.Cu" "B.Mask" "B.Paste")
			(net "P12V_AUX")
		)
		(pad "2" smd circle
			(at -0.40005 0 90)
			(size 0 0)
			(layers "B.Cu" "B.Mask" "B.Paste")
			(net "P0V9_RETIMER_CPU0_VMON")
		)
	)
	(footprint ""
		(layer "B.Cu")
		(at 404.218902 -398.942052 90)
		(property "Reference" "C974"
			(at 0 0 90)
			(layer "B.SilkS")
			(hide yes)
			(effects
				(font
					(size 1.27 1.27)
				)
				(justify mirror)
			)
		)
		(property "Value" ""
			(at 0 0 90)
			(layer "B.Fab")
			(effects
				(font
					(size 1.27 1.27)
				)
				(justify mirror)
			)
		)
		(duplicate_pad_numbers_are_jumpers no)
		(fp_line
			(start 0.7874 -0.4064)
			(end -0.7874 -0.4064)
			(stroke
				(width 0.1524)
				(type default)
			)
			(layer "B.SilkS")
		)
		(fp_line
			(start -0.7874 -0.4064)
			(end -0.7874 0.4064)
			(stroke
				(width 0.1524)
				(type default)
			)
			(layer "B.SilkS")
		)
		(fp_line
			(start 0.7874 0.4064)
			(end 0.7874 -0.4064)
			(stroke
				(width 0.1524)
				(type default)
			)
			(layer "B.SilkS")
		)
		(fp_line
			(start -0.7874 0.4064)
			(end 0.7874 0.4064)
			(stroke
				(width 0.1524)
				(type default)
			)
			(layer "B.SilkS")
		)
		(fp_line
			(start 0.67945 -0.305054)
			(end 0.12065 -0.305054)
			(stroke
				(width 0.1)
				(type default)
			)
			(layer "B.Fab")
		)
		(fp_line
			(start 0.12065 -0.305054)
			(end 0.12065 -0.2794)
			(stroke
				(width 0.1)
				(type default)
			)
			(layer "B.Fab")
		)
		(fp_line
			(start -0.12065 -0.3048)
			(end -0.67945 -0.3048)
			(stroke
				(width 0.1)
				(type default)
			)
			(layer "B.Fab")
		)
		(fp_line
			(start -0.67945 -0.3048)
			(end -0.67945 0.3048)
			(stroke
				(width 0.1)
				(type default)
			)
			(layer "B.Fab")
		)
		(fp_line
			(start 0.12065 -0.2794)
			(end -0.12065 -0.2794)
			(stroke
				(width 0.1)
				(type default)
			)
			(layer "B.Fab")
		)
		(fp_line
			(start -0.12065 -0.2794)
			(end -0.12065 -0.3048)
			(stroke
				(width 0.1)
				(type default)
			)
			(layer "B.Fab")
		)
		(fp_line
			(start 0.12065 0.2794)
			(end 0.12065 0.3048)
			(stroke
				(width 0.1)
				(type default)
			)
			(layer "B.Fab")
		)
		(fp_line
			(start -0.120396 0.2794)
			(end 0.12065 0.2794)
			(stroke
				(width 0.1)
				(type default)
			)
			(layer "B.Fab")
		)
		(fp_line
			(start 0.67945 0.3048)
			(end 0.67945 -0.305054)
			(stroke
				(width 0.1)
				(type default)
			)
			(layer "B.Fab")
		)
		(fp_line
			(start 0.12065 0.3048)
			(end 0.67945 0.3048)
			(stroke
				(width 0.1)
				(type default)
			)
			(layer "B.Fab")
		)
		(fp_line
			(start -0.120396 0.3048)
			(end -0.120396 0.2794)
			(stroke
				(width 0.1)
				(type default)
			)
			(layer "B.Fab")
		)
		(fp_line
			(start -0.67945 0.3048)
			(end -0.120396 0.3048)
			(stroke
				(width 0.1)
				(type default)
			)
			(layer "B.Fab")
		)
		(pad "1" smd circle
			(at 0.40005 0 270)
			(size 0 0)
			(layers "B.Cu" "B.Mask" "B.Paste")
			(net "P0V9_CPU0_RT2_2A")
		)
		(pad "2" smd circle
			(at -0.40005 0 270)
			(size 0 0)
			(layers "B.Cu" "B.Mask" "B.Paste")
			(net "GND")
		)
	)
	(footprint ""
		(layer "B.Cu")
		(at 302.133 -359.283 180)
		(property "Reference" "C5005"
			(at 0 0 0)
			(layer "B.SilkS")
			(hide yes)
			(effects
				(font
					(size 1.27 1.27)
				)
				(justify mirror)
			)
		)
		(property "Value" ""
			(at 0 0 0)
			(layer "B.Fab")
			(effects
				(font
					(size 1.27 1.27)
				)
				(justify mirror)
			)
		)
		(duplicate_pad_numbers_are_jumpers no)
		(fp_line
			(start 0.7874 0.4064)
			(end 0.7874 -0.4064)
			(stroke
				(width 0.1524)
				(type default)
			)
			(layer "B.SilkS")
		)
		(fp_line
			(start 0.7874 -0.4064)
			(end -0.7874 -0.4064)
			(stroke
				(width 0.1524)
				(type default)
			)
			(layer "B.SilkS")
		)
		(fp_line
			(start -0.7874 0.4064)
			(end 0.7874 0.4064)
			(stroke
				(width 0.1524)
				(type default)
			)
			(layer "B.SilkS")
		)
		(fp_line
			(start -0.7874 -0.4064)
			(end -0.7874 0.4064)
			(stroke
				(width 0.1524)
				(type default)
			)
			(layer "B.SilkS")
		)
		(fp_line
			(start 0.67945 0.3048)
			(end 0.67945 -0.305054)
			(stroke
				(width 0.1)
				(type default)
			)
			(layer "B.Fab")
		)
		(fp_line
			(start 0.67945 -0.305054)
			(end 0.12065 -0.305054)
			(stroke
				(width 0.1)
				(type default)
			)
			(layer "B.Fab")
		)
		(fp_line
			(start 0.12065 0.3048)
			(end 0.67945 0.3048)
			(stroke
				(width 0.1)
				(type default)
			)
			(layer "B.Fab")
		)
		(fp_line
			(start 0.12065 0.2794)
			(end 0.12065 0.3048)
			(stroke
				(width 0.1)
				(type default)
			)
			(layer "B.Fab")
		)
		(fp_line
			(start 0.12065 -0.2794)
			(end -0.12065 -0.2794)
			(stroke
				(width 0.1)
				(type default)
			)
			(layer "B.Fab")
		)
		(fp_line
			(start 0.12065 -0.305054)
			(end 0.12065 -0.2794)
			(stroke
				(width 0.1)
				(type default)
			)
			(layer "B.Fab")
		)
		(fp_line
			(start -0.120396 0.3048)
			(end -0.120396 0.2794)
			(stroke
				(width 0.1)
				(type default)
			)
			(layer "B.Fab")
		)
		(fp_line
			(start -0.120396 0.2794)
			(end 0.12065 0.2794)
			(stroke
				(width 0.1)
				(type default)
			)
			(layer "B.Fab")
		)
		(fp_line
			(start -0.12065 -0.2794)
			(end -0.12065 -0.3048)
			(stroke
				(width 0.1)
				(type default)
			)
			(layer "B.Fab")
		)
		(fp_line
			(start -0.12065 -0.3048)
			(end -0.67945 -0.3048)
			(stroke
				(width 0.1)
				(type default)
			)
			(layer "B.Fab")
		)
		(fp_line
			(start -0.67945 0.3048)
			(end -0.120396 0.3048)
			(stroke
				(width 0.1)
				(type default)
			)
			(layer "B.Fab")
		)
		(fp_line
			(start -0.67945 -0.3048)
			(end -0.67945 0.3048)
			(stroke
				(width 0.1)
				(type default)
			)
			(layer "B.Fab")
		)
		(pad "1" smd circle
			(at 0.40005 0)
			(size 0 0)
			(layers "B.Cu" "B.Mask" "B.Paste")
			(net "GND")
		)
		(pad "2" smd circle
			(at -0.40005 0)
			(size 0 0)
			(layers "B.Cu" "B.Mask" "B.Paste")
			(net "PWRGD_PVDDIO_P0")
		)
	)
)
